# S9S_MB_2U (Grand Teton) — schematic netlist excerpt (pin names and nets, part order shuffled) for the footprints in the layout excerpt that follows; sources: Cadence DE-HDL packaged netlist, KiCad conversion of 03242023_DA0F0TMBIJ0_F0T_Motherboard_J_brd_V01_OCP.brd

C465  Q_CAP  47UF 2.5V 20% X6S  pkg C0603  page 78 : A = PVCCFA_EHV_FIVRA_CPU1 ; B = GND
C1924  Q_CAP  0.1UF 25V 10% X7R  pkg 0402  page 190 : A = P3V3_M2_0 ; B = GND

(kicad_pcb
	(version 20260206)
	(generator "pcbnew")
	(generator_version "10.0")
	(general
		(thickness 1.6)
		(legacy_teardrops no)
	)
	(paper "A4")
	(title_block
		(title "03242023_DA0F0TMBIJ0_F0T_Motherboard_J_brd_V01_OCP.brd")
		(comment 1 "Grand Teton / footprints 5751-5752 of 6105")
	)
	(layers
		(0 "F.Cu" signal "TOP")
		(4 "In1.Cu" signal "GND")
		(6 "In2.Cu" signal "IN1")
		(8 "In3.Cu" signal "GND1")
		(10 "In4.Cu" signal "IN2")
		(12 "In5.Cu" signal "GND2")
		(14 "In6.Cu" signal "IN3")
		(16 "In7.Cu" signal "GND3")
		(18 "In8.Cu" signal "VCC")
		(20 "In9.Cu" signal "VCC1")
		(22 "In10.Cu" signal "GND4")
		(24 "In11.Cu" signal "IN4")
		(26 "In12.Cu" signal "GND5")
		(28 "In13.Cu" signal "IN5")
		(30 "In14.Cu" signal "GND6")
		(32 "In15.Cu" signal "IN6")
		(34 "In16.Cu" signal "GND7")
		(2 "B.Cu" signal "BOTTOM")
		(9 "F.Adhes" user "F.Adhesive")
		(11 "B.Adhes" user "B.Adhesive")
		(13 "F.Paste" user "Package Geometry/Pastemask Top")
		(15 "B.Paste" user "Package Geometry/Pastemask Bottom")
		(5 "F.SilkS" user "Ref Des/Silkscreen Top")
		(7 "B.SilkS" user "Ref Des/Silkscreen Bottom")
		(1 "F.Mask" user "Board Geometry/Soldermask Top")
		(3 "B.Mask" user "Board Geometry/Soldermask Bottom")
		(17 "Dwgs.User" user "User.Drawings")
		(19 "Cmts.User" user "User.Comments")
		(21 "Eco1.User" user "User.Eco1")
		(23 "Eco2.User" user "User.Eco2")
		(25 "Edge.Cuts" user "Board Geometry/Outline")
		(27 "Margin" user)
		(31 "F.CrtYd" user "Package Geometry/Place Bound Top")
		(29 "B.CrtYd" user "Package Geometry/Place Bound Bottom")
		(35 "F.Fab" user "Ref Des/Assembly Top")
		(33 "B.Fab" user "Ref Des/Assembly Bottom")
	)
	(footprint ""
		(layer "B.Cu")
		(at 169.66692 -52.415948 180)
		(property "Reference" "C1924"
			(at 0 0 0)
			(layer "B.SilkS")
			(hide yes)
			(effects
				(font
					(size 1.27 1.27)
				)
				(justify mirror)
			)
		)
		(property "Value" ""
			(at 0 0 0)
			(layer "B.Fab")
			(effects
				(font
					(size 1.27 1.27)
				)
				(justify mirror)
			)
		)
		(duplicate_pad_numbers_are_jumpers no)
		(fp_line
			(start 0.7874 0.4064)
			(end 0.7874 -0.4064)
			(stroke
				(width 0.1524)
				(type default)
			)
			(layer "B.SilkS")
		)
		(fp_line
			(start 0.7874 -0.4064)
			(end -0.7874 -0.4064)
			(stroke
				(width 0.1524)
				(type default)
			)
			(layer "B.SilkS")
		)
		(fp_line
			(start -0.7874 0.4064)
			(end 0.7874 0.4064)
			(stroke
				(width 0.1524)
				(type default)
			)
			(layer "B.SilkS")
		)
		(fp_line
			(start -0.7874 -0.4064)
			(end -0.7874 0.4064)
			(stroke
				(width 0.1524)
				(type default)
			)
			(layer "B.SilkS")
		)
		(fp_line
			(start 0.67945 0.3048)
			(end 0.67945 -0.305054)
			(stroke
				(width 0.1)
				(type default)
			)
			(layer "B.Fab")
		)
		(fp_line
			(start 0.67945 -0.305054)
			(end 0.12065 -0.305054)
			(stroke
				(width 0.1)
				(type default)
			)
			(layer "B.Fab")
		)
		(fp_line
			(start 0.12065 0.3048)
			(end 0.67945 0.3048)
			(stroke
				(width 0.1)
				(type default)
			)
			(layer "B.Fab")
		)
		(fp_line
			(start 0.12065 0.2794)
			(end 0.12065 0.3048)
			(stroke
				(width 0.1)
				(type default)
			)
			(layer "B.Fab")
		)
		(fp_line
			(start 0.12065 -0.2794)
			(end -0.12065 -0.2794)
			(stroke
				(width 0.1)
				(type default)
			)
			(layer "B.Fab")
		)
		(fp_line
			(start 0.12065 -0.305054)
			(end 0.12065 -0.2794)
			(stroke
				(width 0.1)
				(type default)
			)
			(layer "B.Fab")
		)
		(fp_line
			(start -0.120396 0.3048)
			(end -0.120396 0.2794)
			(stroke
				(width 0.1)
				(type default)
			)
			(layer "B.Fab")
		)
		(fp_line
			(start -0.120396 0.2794)
			(end 0.12065 0.2794)
			(stroke
				(width 0.1)
				(type default)
			)
			(layer "B.Fab")
		)
		(fp_line
			(start -0.12065 -0.2794)
			(end -0.12065 -0.3048)
			(stroke
				(width 0.1)
				(type default)
			)
			(layer "B.Fab")
		)
		(fp_line
			(start -0.12065 -0.3048)
			(end -0.67945 -0.3048)
			(stroke
				(width 0.1)
				(type default)
			)
			(layer "B.Fab")
		)
		(fp_line
			(start -0.67945 0.3048)
			(end -0.120396 0.3048)
			(stroke
				(width 0.1)
				(type default)
			)
			(layer "B.Fab")
		)
		(fp_line
			(start -0.67945 -0.3048)
			(end -0.67945 0.3048)
			(stroke
				(width 0.1)
				(type default)
			)
			(layer "B.Fab")
		)
		(pad "1" smd circle
			(at 0.40005 0)
			(size 0 0)
			(layers "B.Cu" "B.Mask" "B.Paste")
			(net "P3V3_M2_0")
		)
		(pad "2" smd circle
			(at -0.40005 0)
			(size 0 0)
			(layers "B.Cu" "B.Mask" "B.Paste")
			(net "GND")
		)
	)
	(footprint ""
		(layer "B.Cu")
		(at 120.26392 -237.709456 90)
		(property "Reference" "C465"
			(at 0 0 90)
			(layer "B.SilkS")
			(hide yes)
			(effects
				(font
					(size 1.27 1.27)
				)
				(justify mirror)
			)
		)
		(property "Value" ""
			(at 0 0 90)
			(layer "B.Fab")
			(effects
				(font
					(size 1.27 1.27)
				)
				(justify mirror)
			)
		)
		(duplicate_pad_numbers_are_jumpers no)
		(fp_line
			(start 1.2954 -0.5842)
			(end -1.2954 -0.5842)
			(stroke
				(width 0.1524)
				(type default)
			)
			(layer "B.SilkS")
		)
		(fp_line
			(start 0 -0.5842)
			(end 0 0.5842)
			(stroke
				(width 0.1524)
				(type default)
			)
			(layer "B.SilkS")
		)
		(fp_line
			(start -1.2954 -0.5842)
			(end -1.2954 0.5842)
			(stroke
				(width 0.1524)
				(type default)
			)
			(layer "B.SilkS")
		)
		(fp_line
			(start 1.2954 0.5842)
			(end 1.2954 -0.5842)
			(stroke
				(width 0.1524)
				(type default)
			)
			(layer "B.SilkS")
		)
		(fp_line
			(start -1.2954 0.5842)
			(end 1.2954 0.5842)
			(stroke
				(width 0.1524)
				(type default)
			)
			(layer "B.SilkS")
		)
		(fp_line
			(start 0.8636 -0.4572)
			(end -0.8636 -0.4572)
			(stroke
				(width 0.1)
				(type default)
			)
			(layer "B.Fab")
		)
		(fp_line
			(start -0.8636 -0.4572)
			(end -0.8636 -0.4064)
			(stroke
				(width 0.1)
				(type default)
			)
			(layer "B.Fab")
		)
		(fp_line
			(start 1.1938 -0.4064)
			(end 0.8636 -0.4064)
			(stroke
				(width 0.1)
				(type default)
			)
			(layer "B.Fab")
		)
		(fp_line
			(start 0.8636 -0.4064)
			(end 0.8636 -0.4572)
			(stroke
				(width 0.1)
				(type default)
			)
			(layer "B.Fab")
		)
		(fp_line
			(start -0.8636 -0.4064)
			(end -1.1938 -0.4064)
			(stroke
				(width 0.1)
				(type default)
			)
			(layer "B.Fab")
		)
		(fp_line
			(start -1.1938 -0.4064)
			(end -1.1938 0.4064)
			(stroke
				(width 0.1)
				(type default)
			)
			(layer "B.Fab")
		)
		(fp_line
			(start 1.1938 0.4064)
			(end 1.1938 -0.4064)
			(stroke
				(width 0.1)
				(type default)
			)
			(layer "B.Fab")
		)
		(fp_line
			(start 0.8636 0.4064)
			(end 1.1938 0.4064)
			(stroke
				(width 0.1)
				(type default)
			)
			(layer "B.Fab")
		)
		(fp_line
			(start -0.8636 0.4064)
			(end -0.8636 0.4572)
			(stroke
				(width 0.1)
				(type default)
			)
			(layer "B.Fab")
		)
		(fp_line
			(start -1.1938 0.4064)
			(end -0.8636 0.4064)
			(stroke
				(width 0.1)
				(type default)
			)
			(layer "B.Fab")
		)
		(fp_line
			(start 0.8636 0.4572)
			(end 0.8636 0.4064)
			(stroke
				(width 0.1)
				(type default)
			)
			(layer "B.Fab")
		)
		(fp_line
			(start -0.8636 0.4572)
			(end 0.8636 0.4572)
			(stroke
				(width 0.1)
				(type default)
			)
			(layer "B.Fab")
		)
		(pad "1" smd rect
			(at 0.7366 0)
			(size 0.7112 0.8128)
			(layers "B.Cu" "B.Mask" "B.Paste")
			(net "PVCCFA_EHV_FIVRA_CPU1")
		)
		(pad "2" smd rect
			(at -0.7366 0)
			(size 0.7112 0.8128)
			(layers "B.Cu" "B.Mask" "B.Paste")
			(net "GND")
		)
	)
)
